# BASEBOARD_FAB2 (Tioga Pass) — schematic netlist excerpt (pin names and nets, part order shuffled) for the footprints in the layout excerpt that follows; sources: Cadence DE-HDL packaged netlist, KiCad conversion of Wiwynn_Tioga_Pass_MB.brd

C8E9  SC22U16V5MX-4-GP  20%  pkg SMD-BCG5  page 241 : \1\ = P5V_STBY ; \2\ = GND
C6D1  CAP  10UF 4V 20% X6S  pkg 0603LF  page 38 : A = P1V8_MCP_CPU0 ; B = GND
C5G7  CAP_A  47UF 4V 20% X5R  pkg 0603V  page 217 : A = PVDDQ_ABC ; B = GND

(kicad_pcb
	(version 20260206)
	(generator "pcbnew")
	(generator_version "10.0")
	(general
		(thickness 1.6)
		(legacy_teardrops no)
	)
	(paper "A4")
	(title_block
		(title "Wiwynn_Tioga_Pass_MB.brd")
		(comment 1 "Tioga Pass / footprints 2051-2053 of 4770")
	)
	(layers
		(0 "F.Cu" signal "TOP")
		(4 "In1.Cu" signal "L2GND")
		(6 "In2.Cu" signal "L3")
		(8 "In3.Cu" signal "L4GND")
		(10 "In4.Cu" signal "L5")
		(12 "In5.Cu" signal "L6GND")
		(14 "In6.Cu" signal "L7VCC")
		(16 "In7.Cu" signal "L8VCC")
		(18 "In8.Cu" signal "L9GND")
		(20 "In9.Cu" signal "L10")
		(22 "In10.Cu" signal "L11GND")
		(24 "In11.Cu" signal "L12")
		(26 "In12.Cu" signal "L13GND")
		(2 "B.Cu" signal "BOTTOM")
		(9 "F.Adhes" user "F.Adhesive")
		(11 "B.Adhes" user "B.Adhesive")
		(13 "F.Paste" user "Package Geometry/Pastemask Top")
		(15 "B.Paste" user "Package Geometry/Pastemask Bottom")
		(5 "F.SilkS" user "Ref Des/Silkscreen Top")
		(7 "B.SilkS" user "Ref Des/Silkscreen Bottom")
		(1 "F.Mask" user "Board Geometry/Soldermask Top")
		(3 "B.Mask" user "Board Geometry/Soldermask Bottom")
		(17 "Dwgs.User" user "User.Drawings")
		(19 "Cmts.User" user "User.Comments")
		(21 "Eco1.User" user "User.Eco1")
		(23 "Eco2.User" user "User.Eco2")
		(25 "Edge.Cuts" user "Board Geometry/Outline")
		(27 "Margin" user)
		(31 "F.CrtYd" user "Package Geometry/Place Bound Top")
		(29 "B.CrtYd" user "Package Geometry/Place Bound Bottom")
		(35 "F.Fab" user "Ref Des/Assembly Top")
		(33 "B.Fab" user "Ref Des/Assembly Bottom")
	)
	(footprint ""
		(layer "F.Cu")
		(at 272.861532 -12.954 90)
		(property "Reference" "C5G7"
			(at 1.848866 0.752348 90)
			(unlocked yes)
			(layer "F.SilkS")
			(effects
				(font
					(size 1.27 0.9652)
					(thickness 0.1524)
				)
			)
		)
		(property "Value" ""
			(at 0 0 90)
			(layer "F.Fab")
			(effects
				(font
					(size 1.27 1.27)
				)
			)
		)
		(duplicate_pad_numbers_are_jumpers no)
		(fp_rect
			(start -0.500126 1.598422)
			(end 0.500126 -0.201422)
			(stroke
				(width 0)
				(type default)
			)
			(fill no)
			(layer "F.CrtYd")
		)
		(fp_line
			(start 0.500126 -0.201422)
			(end 0.500126 1.598422)
			(stroke
				(width 0.1)
				(type default)
			)
			(layer "F.Fab")
		)
		(fp_line
			(start -0.500126 -0.201422)
			(end 0.500126 -0.201422)
			(stroke
				(width 0.1)
				(type default)
			)
			(layer "F.Fab")
		)
		(fp_line
			(start 0.500126 1.598422)
			(end -0.500126 1.598422)
			(stroke
				(width 0.1)
				(type default)
			)
			(layer "F.Fab")
		)
		(fp_line
			(start -0.500126 1.598422)
			(end -0.500126 -0.201422)
			(stroke
				(width 0.1)
				(type default)
			)
			(layer "F.Fab")
		)
		(pad "1" smd rect
			(at 0 0)
			(size 0.889 0.9906)
			(layers "F.Cu" "F.Mask" "F.Paste")
			(net "PVDDQ_ABC")
		)
		(pad "2" smd rect
			(at 0 1.397)
			(size 0.889 0.9906)
			(layers "F.Cu" "F.Mask" "F.Paste")
			(net "GND")
		)
		(zone
			(layer "F.Cu")
			(hatch none 0.5)
			(connect_pads
				(clearance 0)
			)
			(min_thickness 0.25)
			(keepout
				(tracks allowed)
				(vias not_allowed)
				(pads allowed)
				(copperpour not_allowed)
				(footprints allowed)
			)
			(placement
				(enabled no)
				(sheetname "")
			)
			(fill
				(thermal_gap 0.5)
				(thermal_bridge_width 0.5)
				(island_removal_mode 0)
			)
			(polygon
				(pts
					(xy 273.814032 -12.4587) (xy 273.814032 -13.4493) (xy 273.306032 -13.4493) (xy 273.306032 -12.4587)
				)
			)
		)
		(zone
			(layer "F.Cu")
			(hatch none 0.5)
			(connect_pads
				(clearance 0)
			)
			(min_thickness 0.25)
			(keepout
				(tracks not_allowed)
				(vias allowed)
				(pads allowed)
				(copperpour not_allowed)
				(footprints allowed)
			)
			(placement
				(enabled no)
				(sheetname "")
			)
			(fill
				(thermal_gap 0.5)
				(thermal_bridge_width 0.5)
				(island_removal_mode 0)
			)
			(polygon
				(pts
					(xy 273.814032 -12.4587) (xy 273.814032 -13.4493) (xy 273.306032 -13.4493) (xy 273.306032 -12.4587)
				)
			)
		)
	)
	(footprint ""
		(layer "F.Cu")
		(at 281.776424 -80.9371)
		(property "Reference" "C6D1"
			(at 0 0 0)
			(layer "F.SilkS")
			(hide yes)
			(effects
				(font
					(size 1.27 1.27)
				)
			)
		)
		(property "Value" ""
			(at 0 0 0)
			(layer "F.Fab")
			(effects
				(font
					(size 1.27 1.27)
				)
			)
		)
		(duplicate_pad_numbers_are_jumpers no)
		(fp_poly
			(pts
				(xy -0.4953 -0.2032) (xy 0.4953 -0.2032) (xy 0.4953 1.6002) (xy -0.4953 1.6002)
			)
			(stroke
				(width 0)
				(type default)
			)
			(fill no)
			(layer "F.CrtYd")
		)
		(fp_line
			(start -0.4953 -0.2032)
			(end 0.4953 -0.2032)
			(stroke
				(width 0.1)
				(type default)
			)
			(layer "F.Fab")
		)
		(fp_line
			(start -0.4953 1.6002)
			(end -0.4953 -0.2032)
			(stroke
				(width 0.1)
				(type default)
			)
			(layer "F.Fab")
		)
		(fp_line
			(start 0.4953 -0.2032)
			(end 0.4953 1.6002)
			(stroke
				(width 0.1)
				(type default)
			)
			(layer "F.Fab")
		)
		(fp_line
			(start 0.4953 1.6002)
			(end -0.4953 1.6002)
			(stroke
				(width 0.1)
				(type default)
			)
			(layer "F.Fab")
		)
		(pad "1" smd rect
			(at 0 0)
			(size 0.762 0.889)
			(layers "F.Cu" "F.Mask" "F.Paste")
			(net "P1V8_MCP_CPU0")
		)
		(pad "2" smd rect
			(at 0 1.397)
			(size 0.762 0.889)
			(layers "F.Cu" "F.Mask" "F.Paste")
			(net "GND")
		)
		(zone
			(layer "F.Cu")
			(hatch none 0.5)
			(connect_pads
				(clearance 0)
			)
			(min_thickness 0.25)
			(keepout
				(tracks not_allowed)
				(vias allowed)
				(pads allowed)
				(copperpour not_allowed)
				(footprints allowed)
			)
			(placement
				(enabled no)
				(sheetname "")
			)
			(fill
				(thermal_gap 0.5)
				(thermal_bridge_width 0.5)
				(island_removal_mode 0)
			)
			(polygon
				(pts
					(xy 281.395424 -80.4926) (xy 282.157424 -80.4926) (xy 282.157424 -79.9846) (xy 281.395424 -79.9846)
				)
			)
		)
	)
	(footprint ""
		(layer "F.Cu")
		(at 405.47036 -57.79389)
		(property "Reference" "C8E9"
			(at 0 0 0)
			(layer "F.SilkS")
			(hide yes)
			(effects
				(font
					(size 1.27 1.27)
				)
			)
		)
		(property "Value" "*"
			(at -0.0762 -6.2357 0)
			(unlocked yes)
			(layer "F.Fab")
			(hide yes)
			(effects
				(font
					(size 1.27 1.016)
					(thickness 0.1524)
				)
			)
		)
		(property "Device Type" "SC22U16V5MX-4-GP_SMD-BCG5-SC22A"
			(at -0.0762 -8.2677 0)
			(unlocked yes)
			(layer "F.Fab")
			(hide yes)
			(effects
				(font
					(size 1.27 1.016)
					(thickness 0.1524)
				)
			)
		)
		(duplicate_pad_numbers_are_jumpers no)
		(fp_line
			(start 0.635 0)
			(end -0.635 0)
			(stroke
				(width 0.508)
				(type default)
			)
			(layer "F.SilkS")
		)
		(fp_rect
			(start -0.9652 1.778)
			(end 0.9652 -1.778)
			(stroke
				(width 0)
				(type default)
			)
			(fill no)
			(layer "F.CrtYd")
		)
		(fp_poly
			(pts
				(xy -0.9652 -1.778) (xy 0.9652 -1.778) (xy 0.9652 1.778) (xy -0.9652 1.778)
			)
			(stroke
				(width 0)
				(type default)
			)
			(fill no)
			(layer "F.Fab")
		)
		(pad "1" smd rect
			(at 0 -0.9652)
			(size 1.397 1.143)
			(layers "F.Cu" "F.Mask" "F.Paste")
			(net "P5V_STBY")
		)
		(pad "2" smd rect
			(at 0 0.9652)
			(size 1.397 1.143)
			(layers "F.Cu" "F.Mask" "F.Paste")
			(net "GND")
		)
	)
)
